# S9S_MB_2U (Grand Teton) — schematic netlist excerpt (pin names and nets, part order shuffled) for the footprints in the layout excerpt that follows; sources: Cadence DE-HDL packaged netlist, KiCad conversion of 03242023_DA0F0TMBIJ0_F0T_Motherboard_J_brd_V01_OCP.brd

R4773  Q_RES  10K 1% EMPTY  pkg 0402LF  page 307 : A = P3V3_AUX ; B = UV_P2V5_COMP

U342  AP331AWG7  AP331AWG-7 EMPTY  pkg SOT25  page 307
  \in-\  = DSW_PWROK_P2V5_COMP
  GND  = GND
  \in+\  = PWRGD_DSW_PWROK_TRIGGER
  OUTPUT  = PWRGD_DSW_PWROK_R5
  VCC  = P12V_AUX

(kicad_pcb
	(version 20260206)
	(generator "pcbnew")
	(generator_version "10.0")
	(general
		(thickness 1.6)
		(legacy_teardrops no)
	)
	(paper "A4")
	(title_block
		(title "03242023_DA0F0TMBIJ0_F0T_Motherboard_J_brd_V01_OCP.brd")
		(comment 1 "Grand Teton / footprints 352-353 of 6105")
	)
	(layers
		(0 "F.Cu" signal "TOP")
		(4 "In1.Cu" signal "GND")
		(6 "In2.Cu" signal "IN1")
		(8 "In3.Cu" signal "GND1")
		(10 "In4.Cu" signal "IN2")
		(12 "In5.Cu" signal "GND2")
		(14 "In6.Cu" signal "IN3")
		(16 "In7.Cu" signal "GND3")
		(18 "In8.Cu" signal "VCC")
		(20 "In9.Cu" signal "VCC1")
		(22 "In10.Cu" signal "GND4")
		(24 "In11.Cu" signal "IN4")
		(26 "In12.Cu" signal "GND5")
		(28 "In13.Cu" signal "IN5")
		(30 "In14.Cu" signal "GND6")
		(32 "In15.Cu" signal "IN6")
		(34 "In16.Cu" signal "GND7")
		(2 "B.Cu" signal "BOTTOM")
		(9 "F.Adhes" user "F.Adhesive")
		(11 "B.Adhes" user "B.Adhesive")
		(13 "F.Paste" user "Package Geometry/Pastemask Top")
		(15 "B.Paste" user "Package Geometry/Pastemask Bottom")
		(5 "F.SilkS" user "Ref Des/Silkscreen Top")
		(7 "B.SilkS" user "Ref Des/Silkscreen Bottom")
		(1 "F.Mask" user "Board Geometry/Soldermask Top")
		(3 "B.Mask" user "Board Geometry/Soldermask Bottom")
		(17 "Dwgs.User" user "User.Drawings")
		(19 "Cmts.User" user "User.Comments")
		(21 "Eco1.User" user "User.Eco1")
		(23 "Eco2.User" user "User.Eco2")
		(25 "Edge.Cuts" user "Board Geometry/Outline")
		(27 "Margin" user)
		(31 "F.CrtYd" user "Package Geometry/Place Bound Top")
		(29 "B.CrtYd" user "Package Geometry/Place Bound Bottom")
		(35 "F.Fab" user "Ref Des/Assembly Top")
		(33 "B.Fab" user "Ref Des/Assembly Bottom")
	)
	(footprint ""
		(layer "F.Cu")
		(at 308.4068 -26.3652)
		(property "Reference" "U342"
			(at 5.0927 -1.85801 0)
			(unlocked yes)
			(layer "F.SilkS")
			(effects
				(font
					(size 0.7874 0.5842)
					(thickness 0.1524)
				)
			)
		)
		(property "Value" ""
			(at 0 0 0)
			(layer "F.Fab")
			(effects
				(font
					(size 1.27 1.27)
				)
			)
		)
		(duplicate_pad_numbers_are_jumpers no)
		(fp_line
			(start -2.032 -1.549908)
			(end -0.508 -1.549908)
			(stroke
				(width 0.1524)
				(type default)
			)
			(layer "F.SilkS")
		)
		(fp_line
			(start -2.032 1.549908)
			(end -2.032 -1.549908)
			(stroke
				(width 0.1524)
				(type default)
			)
			(layer "F.SilkS")
		)
		(fp_line
			(start -0.508 -1.549908)
			(end 0 -0.762)
			(stroke
				(width 0.1524)
				(type default)
			)
			(layer "F.SilkS")
		)
		(fp_line
			(start 0 -0.762)
			(end 0.508 -1.549908)
			(stroke
				(width 0.1524)
				(type default)
			)
			(layer "F.SilkS")
		)
		(fp_line
			(start 0.508 -1.549908)
			(end 2.032 -1.549908)
			(stroke
				(width 0.1524)
				(type default)
			)
			(layer "F.SilkS")
		)
		(fp_line
			(start 2.032 -1.549908)
			(end 2.032 1.549908)
			(stroke
				(width 0.1524)
				(type default)
			)
			(layer "F.SilkS")
		)
		(fp_line
			(start 2.032 1.549908)
			(end -2.032 1.549908)
			(stroke
				(width 0.1524)
				(type default)
			)
			(layer "F.SilkS")
		)
		(fp_poly
			(pts
				(xy -3.2004 -1.45796) (xy -3.2004 -0.44196) (xy -2.1844 -0.94996)
			)
			(stroke
				(width 0)
				(type default)
			)
			(fill yes)
			(layer "F.SilkS")
		)
		(fp_line
			(start -0.849884 -1.549908)
			(end 0.849884 -1.549908)
			(stroke
				(width 0.1)
				(type default)
			)
			(layer "F.Fab")
		)
		(fp_line
			(start -0.849884 1.549908)
			(end -0.849884 -1.549908)
			(stroke
				(width 0.1)
				(type default)
			)
			(layer "F.Fab")
		)
		(fp_line
			(start 0.849884 -1.549908)
			(end 0.849884 1.549908)
			(stroke
				(width 0.1)
				(type default)
			)
			(layer "F.Fab")
		)
		(fp_line
			(start 0.849884 1.549908)
			(end -0.849884 1.549908)
			(stroke
				(width 0.1)
				(type default)
			)
			(layer "F.Fab")
		)
		(fp_poly
			(pts
				(xy -3.2004 -1.45796) (xy -3.2004 -0.44196) (xy -2.1844 -0.94996)
			)
			(stroke
				(width 0)
				(type default)
			)
			(fill yes)
			(layer "F.Fab")
		)
		(pad "1" smd rect
			(at -1.35001 -0.94996 270)
			(size 0.6096 1.0668)
			(layers "F.Cu" "F.Mask" "F.Paste")
			(net "DSW_PWROK_P2V5_COMP")
		)
		(pad "2" smd rect
			(at -1.35001 0 270)
			(size 0.6096 1.0668)
			(layers "F.Cu" "F.Mask" "F.Paste")
			(net "GND")
		)
		(pad "3" smd rect
			(at -1.35001 0.94996 270)
			(size 0.6096 1.0668)
			(layers "F.Cu" "F.Mask" "F.Paste")
			(net "PWRGD_DSW_PWROK_TRIGGER")
		)
		(pad "4" smd rect
			(at 1.35001 0.94996 270)
			(size 0.6096 1.0668)
			(layers "F.Cu" "F.Mask" "F.Paste")
			(net "PWRGD_DSW_PWROK_R5")
		)
		(pad "5" smd rect
			(at 1.35001 -0.94996 270)
			(size 0.6096 1.0668)
			(layers "F.Cu" "F.Mask" "F.Paste")
			(net "P12V_AUX")
		)
	)
	(footprint ""
		(layer "F.Cu")
		(at 209.931 -114.0968 180)
		(property "Reference" "R4773"
			(at 0 0 180)
			(layer "F.SilkS")
			(hide yes)
			(effects
				(font
					(size 1.27 1.27)
				)
			)
		)
		(property "Value" ""
			(at 0 0 180)
			(layer "F.Fab")
			(effects
				(font
					(size 1.27 1.27)
				)
			)
		)
		(duplicate_pad_numbers_are_jumpers no)
		(fp_line
			(start 0.7874 0.4064)
			(end -0.7874 0.4064)
			(stroke
				(width 0.1524)
				(type default)
			)
			(layer "F.SilkS")
		)
		(fp_line
			(start 0.7874 -0.4064)
			(end 0.7874 0.4064)
			(stroke
				(width 0.1524)
				(type default)
			)
			(layer "F.SilkS")
		)
		(fp_line
			(start -0.7874 0.4064)
			(end -0.7874 -0.4064)
			(stroke
				(width 0.1524)
				(type default)
			)
			(layer "F.SilkS")
		)
		(fp_line
			(start -0.7874 -0.4064)
			(end 0.7874 -0.4064)
			(stroke
				(width 0.1524)
				(type default)
			)
			(layer "F.SilkS")
		)
		(fp_line
			(start 0.67945 0.3048)
			(end 0.120396 0.3048)
			(stroke
				(width 0.1)
				(type default)
			)
			(layer "F.Fab")
		)
		(fp_line
			(start 0.67945 -0.3048)
			(end 0.67945 0.3048)
			(stroke
				(width 0.1)
				(type default)
			)
			(layer "F.Fab")
		)
		(fp_line
			(start 0.12065 -0.2794)
			(end 0.12065 -0.3048)
			(stroke
				(width 0.1)
				(type default)
			)
			(layer "F.Fab")
		)
		(fp_line
			(start 0.12065 -0.3048)
			(end 0.67945 -0.3048)
			(stroke
				(width 0.1)
				(type default)
			)
			(layer "F.Fab")
		)
		(fp_line
			(start 0.120396 0.3048)
			(end 0.120396 0.2794)
			(stroke
				(width 0.1)
				(type default)
			)
			(layer "F.Fab")
		)
		(fp_line
			(start 0.120396 0.2794)
			(end -0.12065 0.2794)
			(stroke
				(width 0.1)
				(type default)
			)
			(layer "F.Fab")
		)
		(fp_line
			(start -0.12065 0.3048)
			(end -0.67945 0.3048)
			(stroke
				(width 0.1)
				(type default)
			)
			(layer "F.Fab")
		)
		(fp_line
			(start -0.12065 0.2794)
			(end -0.12065 0.3048)
			(stroke
				(width 0.1)
				(type default)
			)
			(layer "F.Fab")
		)
		(fp_line
			(start -0.12065 -0.2794)
			(end 0.12065 -0.2794)
			(stroke
				(width 0.1)
				(type default)
			)
			(layer "F.Fab")
		)
		(fp_line
			(start -0.12065 -0.305054)
			(end -0.12065 -0.2794)
			(stroke
				(width 0.1)
				(type default)
			)
			(layer "F.Fab")
		)
		(fp_line
			(start -0.67945 0.3048)
			(end -0.67945 -0.305054)
			(stroke
				(width 0.1)
				(type default)
			)
			(layer "F.Fab")
		)
		(fp_line
			(start -0.67945 -0.305054)
			(end -0.12065 -0.305054)
			(stroke
				(width 0.1)
				(type default)
			)
			(layer "F.Fab")
		)
		(pad "1" smd circle
			(at -0.40005 0 180)
			(size 0 0)
			(layers "F.Cu" "F.Mask" "F.Paste")
			(net "P3V3_AUX")
		)
		(pad "2" smd circle
			(at 0.40005 0 180)
			(size 0 0)
			(layers "F.Cu" "F.Mask" "F.Paste")
			(net "UV_P2V5_COMP")
		)
	)
)
